# T6G (Grand Teton) — schematic netlist excerpt (pin names and nets, part order shuffled) for the footprints in the layout excerpt that follows; sources: Cadence DE-HDL packaged netlist, KiCad conversion of 04192023_DAF0TMB3IC0_F0TG_MB_C_brd_V02_OCP.brd

R8308  Q_RES  0 5% CHIP  pkg 0402LF  page 193 : A = SMB_SCM_2_R3_SCL ; B = PVDDCR_CPU0_P0_PMSCL_R
C2539  Q_CAP  22UF 4V 20% X6S  pkg C0402  page 70 : A = PVDDCR_SOC_P0 ; B = GND

(kicad_pcb
	(version 20260206)
	(generator "pcbnew")
	(generator_version "10.0")
	(general
		(thickness 1.6)
		(legacy_teardrops no)
	)
	(paper "A4")
	(title_block
		(title "04192023_DAF0TMB3IC0_F0TG_MB_C_brd_V02_OCP.brd")
		(comment 1 "Grand Teton / footprints 7070-7071 of 8354")
	)
	(layers
		(0 "F.Cu" signal "TOP")
		(4 "In1.Cu" signal "GND")
		(6 "In2.Cu" signal "IN1")
		(8 "In3.Cu" signal "GND1")
		(10 "In4.Cu" signal "IN2")
		(12 "In5.Cu" signal "GND2")
		(14 "In6.Cu" signal "IN3")
		(16 "In7.Cu" signal "GND3")
		(18 "In8.Cu" signal "VCC")
		(20 "In9.Cu" signal "VCC1")
		(22 "In10.Cu" signal "GND4")
		(24 "In11.Cu" signal "IN4")
		(26 "In12.Cu" signal "GND5")
		(28 "In13.Cu" signal "IN5")
		(30 "In14.Cu" signal "GND6")
		(32 "In15.Cu" signal "IN6")
		(34 "In16.Cu" signal "GND7")
		(2 "B.Cu" signal "BOTTOM")
		(9 "F.Adhes" user "F.Adhesive")
		(11 "B.Adhes" user "B.Adhesive")
		(13 "F.Paste" user "Package Geometry/Pastemask Top")
		(15 "B.Paste" user "Package Geometry/Pastemask Bottom")
		(5 "F.SilkS" user "Ref Des/Silkscreen Top")
		(7 "B.SilkS" user "Ref Des/Silkscreen Bottom")
		(1 "F.Mask" user "Board Geometry/Soldermask Top")
		(3 "B.Mask" user "Board Geometry/Soldermask Bottom")
		(17 "Dwgs.User" user "User.Drawings")
		(19 "Cmts.User" user "User.Comments")
		(21 "Eco1.User" user "User.Eco1")
		(23 "Eco2.User" user "User.Eco2")
		(25 "Edge.Cuts" user "Board Geometry/Outline")
		(27 "Margin" user)
		(31 "F.CrtYd" user "Package Geometry/Place Bound Top")
		(29 "B.CrtYd" user "Package Geometry/Place Bound Bottom")
		(35 "F.Fab" user "Ref Des/Assembly Top")
		(33 "B.Fab" user "Ref Des/Assembly Bottom")
	)
	(footprint ""
		(layer "B.Cu")
		(at 373.337328 -137.008108 -90)
		(property "Reference" "R8308"
			(at 0 0 90)
			(layer "B.SilkS")
			(hide yes)
			(effects
				(font
					(size 1.27 1.27)
				)
				(justify mirror)
			)
		)
		(property "Value" ""
			(at 0 0 90)
			(layer "B.Fab")
			(effects
				(font
					(size 1.27 1.27)
				)
				(justify mirror)
			)
		)
		(duplicate_pad_numbers_are_jumpers no)
		(fp_line
			(start -0.7874 0.4064)
			(end 0.7874 0.4064)
			(stroke
				(width 0.1524)
				(type default)
			)
			(layer "B.SilkS")
		)
		(fp_line
			(start 0.7874 0.4064)
			(end 0.7874 -0.4064)
			(stroke
				(width 0.1524)
				(type default)
			)
			(layer "B.SilkS")
		)
		(fp_line
			(start -0.7874 -0.4064)
			(end -0.7874 0.4064)
			(stroke
				(width 0.1524)
				(type default)
			)
			(layer "B.SilkS")
		)
		(fp_line
			(start 0.7874 -0.4064)
			(end -0.7874 -0.4064)
			(stroke
				(width 0.1524)
				(type default)
			)
			(layer "B.SilkS")
		)
		(fp_line
			(start -0.67945 0.3048)
			(end -0.120396 0.3048)
			(stroke
				(width 0.1)
				(type default)
			)
			(layer "B.Fab")
		)
		(fp_line
			(start -0.120396 0.3048)
			(end -0.120396 0.2794)
			(stroke
				(width 0.1)
				(type default)
			)
			(layer "B.Fab")
		)
		(fp_line
			(start 0.12065 0.3048)
			(end 0.67945 0.3048)
			(stroke
				(width 0.1)
				(type default)
			)
			(layer "B.Fab")
		)
		(fp_line
			(start 0.67945 0.3048)
			(end 0.67945 -0.305054)
			(stroke
				(width 0.1)
				(type default)
			)
			(layer "B.Fab")
		)
		(fp_line
			(start -0.120396 0.2794)
			(end 0.12065 0.2794)
			(stroke
				(width 0.1)
				(type default)
			)
			(layer "B.Fab")
		)
		(fp_line
			(start 0.12065 0.2794)
			(end 0.12065 0.3048)
			(stroke
				(width 0.1)
				(type default)
			)
			(layer "B.Fab")
		)
		(fp_line
			(start -0.12065 -0.2794)
			(end -0.12065 -0.3048)
			(stroke
				(width 0.1)
				(type default)
			)
			(layer "B.Fab")
		)
		(fp_line
			(start 0.12065 -0.2794)
			(end -0.12065 -0.2794)
			(stroke
				(width 0.1)
				(type default)
			)
			(layer "B.Fab")
		)
		(fp_line
			(start -0.67945 -0.3048)
			(end -0.67945 0.3048)
			(stroke
				(width 0.1)
				(type default)
			)
			(layer "B.Fab")
		)
		(fp_line
			(start -0.12065 -0.3048)
			(end -0.67945 -0.3048)
			(stroke
				(width 0.1)
				(type default)
			)
			(layer "B.Fab")
		)
		(fp_line
			(start 0.12065 -0.305054)
			(end 0.12065 -0.2794)
			(stroke
				(width 0.1)
				(type default)
			)
			(layer "B.Fab")
		)
		(fp_line
			(start 0.67945 -0.305054)
			(end 0.12065 -0.305054)
			(stroke
				(width 0.1)
				(type default)
			)
			(layer "B.Fab")
		)
		(pad "1" smd circle
			(at 0.40005 0 90)
			(size 0 0)
			(layers "B.Cu" "B.Mask" "B.Paste")
			(net "SMB_SCM_2_R3_SCL")
		)
		(pad "2" smd circle
			(at -0.40005 0 90)
			(size 0 0)
			(layers "B.Cu" "B.Mask" "B.Paste")
			(net "PVDDCR_CPU0_P0_PMSCL_R")
		)
	)
	(footprint ""
		(layer "B.Cu")
		(at 363.215936 -256.012188 -90)
		(property "Reference" "C2539"
			(at 0 0 90)
			(layer "B.SilkS")
			(hide yes)
			(effects
				(font
					(size 1.27 1.27)
				)
				(justify mirror)
			)
		)
		(property "Value" ""
			(at 0 0 90)
			(layer "B.Fab")
			(effects
				(font
					(size 1.27 1.27)
				)
				(justify mirror)
			)
		)
		(duplicate_pad_numbers_are_jumpers no)
		(fp_line
			(start -0.7874 0.4064)
			(end 0.7874 0.4064)
			(stroke
				(width 0.1524)
				(type default)
			)
			(layer "B.SilkS")
		)
		(fp_line
			(start 0.7874 0.4064)
			(end 0.7874 -0.4064)
			(stroke
				(width 0.1524)
				(type default)
			)
			(layer "B.SilkS")
		)
		(fp_line
			(start -0.7874 -0.4064)
			(end -0.7874 0.4064)
			(stroke
				(width 0.1524)
				(type default)
			)
			(layer "B.SilkS")
		)
		(fp_line
			(start 0.7874 -0.4064)
			(end -0.7874 -0.4064)
			(stroke
				(width 0.1524)
				(type default)
			)
			(layer "B.SilkS")
		)
		(fp_line
			(start -0.67945 0.3048)
			(end -0.120396 0.3048)
			(stroke
				(width 0.1)
				(type default)
			)
			(layer "B.Fab")
		)
		(fp_line
			(start -0.120396 0.3048)
			(end -0.120396 0.2794)
			(stroke
				(width 0.1)
				(type default)
			)
			(layer "B.Fab")
		)
		(fp_line
			(start 0.12065 0.3048)
			(end 0.67945 0.3048)
			(stroke
				(width 0.1)
				(type default)
			)
			(layer "B.Fab")
		)
		(fp_line
			(start 0.67945 0.3048)
			(end 0.67945 -0.305054)
			(stroke
				(width 0.1)
				(type default)
			)
			(layer "B.Fab")
		)
		(fp_line
			(start -0.120396 0.2794)
			(end 0.12065 0.2794)
			(stroke
				(width 0.1)
				(type default)
			)
			(layer "B.Fab")
		)
		(fp_line
			(start 0.12065 0.2794)
			(end 0.12065 0.3048)
			(stroke
				(width 0.1)
				(type default)
			)
			(layer "B.Fab")
		)
		(fp_line
			(start -0.12065 -0.2794)
			(end -0.12065 -0.3048)
			(stroke
				(width 0.1)
				(type default)
			)
			(layer "B.Fab")
		)
		(fp_line
			(start 0.12065 -0.2794)
			(end -0.12065 -0.2794)
			(stroke
				(width 0.1)
				(type default)
			)
			(layer "B.Fab")
		)
		(fp_line
			(start -0.67945 -0.3048)
			(end -0.67945 0.3048)
			(stroke
				(width 0.1)
				(type default)
			)
			(layer "B.Fab")
		)
		(fp_line
			(start -0.12065 -0.3048)
			(end -0.67945 -0.3048)
			(stroke
				(width 0.1)
				(type default)
			)
			(layer "B.Fab")
		)
		(fp_line
			(start 0.12065 -0.305054)
			(end 0.12065 -0.2794)
			(stroke
				(width 0.1)
				(type default)
			)
			(layer "B.Fab")
		)
		(fp_line
			(start 0.67945 -0.305054)
			(end 0.12065 -0.305054)
			(stroke
				(width 0.1)
				(type default)
			)
			(layer "B.Fab")
		)
		(pad "1" smd circle
			(at 0.40005 0 90)
			(size 0 0)
			(layers "B.Cu" "B.Mask" "B.Paste")
			(net "PVDDCR_SOC_P0")
		)
		(pad "2" smd circle
			(at -0.40005 0 90)
			(size 0 0)
			(layers "B.Cu" "B.Mask" "B.Paste")
			(net "GND")
		)
	)
)
